# T6G (Grand Teton) — schematic netlist excerpt (pin names and nets, part order shuffled) for the footprints in the layout excerpt that follows; sources: Cadence DE-HDL packaged netlist, KiCad conversion of 04192023_DAF0TMB3IC0_F0TG_MB_C_brd_V02_OCP.brd

R328  Q_RES  0 5% CHIP  pkg 0402LF  page 161 : A = SMB_APML_CPU0_MUX2_SDA ; B = SMB_APML_CPU0_SDA
C2368  Q_CAP  22UF 4V 20% X6S  pkg C0402  page 73 : A = PVDDCR_CPU1_P1 ; B = GND
R842  Q_RES  4.7K 5% EMPTY  pkg 0201LF  page 185 : A = P1V8_AUX ; B = RT_ROM_SMB_MUX_ADDR2

(kicad_pcb
	(version 20260206)
	(generator "pcbnew")
	(generator_version "10.0")
	(general
		(thickness 1.6)
		(legacy_teardrops no)
	)
	(paper "A4")
	(title_block
		(title "04192023_DAF0TMB3IC0_F0TG_MB_C_brd_V02_OCP.brd")
		(comment 1 "Grand Teton / footprints 5342-5344 of 8354")
	)
	(layers
		(0 "F.Cu" signal "TOP")
		(4 "In1.Cu" signal "GND")
		(6 "In2.Cu" signal "IN1")
		(8 "In3.Cu" signal "GND1")
		(10 "In4.Cu" signal "IN2")
		(12 "In5.Cu" signal "GND2")
		(14 "In6.Cu" signal "IN3")
		(16 "In7.Cu" signal "GND3")
		(18 "In8.Cu" signal "VCC")
		(20 "In9.Cu" signal "VCC1")
		(22 "In10.Cu" signal "GND4")
		(24 "In11.Cu" signal "IN4")
		(26 "In12.Cu" signal "GND5")
		(28 "In13.Cu" signal "IN5")
		(30 "In14.Cu" signal "GND6")
		(32 "In15.Cu" signal "IN6")
		(34 "In16.Cu" signal "GND7")
		(2 "B.Cu" signal "BOTTOM")
		(9 "F.Adhes" user "F.Adhesive")
		(11 "B.Adhes" user "B.Adhesive")
		(13 "F.Paste" user "Package Geometry/Pastemask Top")
		(15 "B.Paste" user "Package Geometry/Pastemask Bottom")
		(5 "F.SilkS" user "Ref Des/Silkscreen Top")
		(7 "B.SilkS" user "Ref Des/Silkscreen Bottom")
		(1 "F.Mask" user "Board Geometry/Soldermask Top")
		(3 "B.Mask" user "Board Geometry/Soldermask Bottom")
		(17 "Dwgs.User" user "User.Drawings")
		(19 "Cmts.User" user "User.Comments")
		(21 "Eco1.User" user "User.Eco1")
		(23 "Eco2.User" user "User.Eco2")
		(25 "Edge.Cuts" user "Board Geometry/Outline")
		(27 "Margin" user)
		(31 "F.CrtYd" user "Package Geometry/Place Bound Top")
		(29 "B.CrtYd" user "Package Geometry/Place Bound Bottom")
		(35 "F.Fab" user "Ref Des/Assembly Top")
		(33 "B.Fab" user "Ref Des/Assembly Bottom")
	)
	(footprint ""
		(layer "B.Cu")
		(at 119.674386 -267.49883)
		(property "Reference" "C2368"
			(at 0 0 0)
			(layer "B.SilkS")
			(hide yes)
			(effects
				(font
					(size 1.27 1.27)
				)
				(justify mirror)
			)
		)
		(property "Value" ""
			(at 0 0 0)
			(layer "B.Fab")
			(effects
				(font
					(size 1.27 1.27)
				)
				(justify mirror)
			)
		)
		(duplicate_pad_numbers_are_jumpers no)
		(fp_line
			(start -0.7874 -0.4064)
			(end -0.7874 0.4064)
			(stroke
				(width 0.1524)
				(type default)
			)
			(layer "B.SilkS")
		)
		(fp_line
			(start -0.7874 0.4064)
			(end 0.7874 0.4064)
			(stroke
				(width 0.1524)
				(type default)
			)
			(layer "B.SilkS")
		)
		(fp_line
			(start 0.7874 -0.4064)
			(end -0.7874 -0.4064)
			(stroke
				(width 0.1524)
				(type default)
			)
			(layer "B.SilkS")
		)
		(fp_line
			(start 0.7874 0.4064)
			(end 0.7874 -0.4064)
			(stroke
				(width 0.1524)
				(type default)
			)
			(layer "B.SilkS")
		)
		(fp_line
			(start -0.67945 -0.3048)
			(end -0.67945 0.3048)
			(stroke
				(width 0.1)
				(type default)
			)
			(layer "B.Fab")
		)
		(fp_line
			(start -0.67945 0.3048)
			(end -0.120396 0.3048)
			(stroke
				(width 0.1)
				(type default)
			)
			(layer "B.Fab")
		)
		(fp_line
			(start -0.12065 -0.3048)
			(end -0.67945 -0.3048)
			(stroke
				(width 0.1)
				(type default)
			)
			(layer "B.Fab")
		)
		(fp_line
			(start -0.12065 -0.2794)
			(end -0.12065 -0.3048)
			(stroke
				(width 0.1)
				(type default)
			)
			(layer "B.Fab")
		)
		(fp_line
			(start -0.120396 0.2794)
			(end 0.12065 0.2794)
			(stroke
				(width 0.1)
				(type default)
			)
			(layer "B.Fab")
		)
		(fp_line
			(start -0.120396 0.3048)
			(end -0.120396 0.2794)
			(stroke
				(width 0.1)
				(type default)
			)
			(layer "B.Fab")
		)
		(fp_line
			(start 0.12065 -0.305054)
			(end 0.12065 -0.2794)
			(stroke
				(width 0.1)
				(type default)
			)
			(layer "B.Fab")
		)
		(fp_line
			(start 0.12065 -0.2794)
			(end -0.12065 -0.2794)
			(stroke
				(width 0.1)
				(type default)
			)
			(layer "B.Fab")
		)
		(fp_line
			(start 0.12065 0.2794)
			(end 0.12065 0.3048)
			(stroke
				(width 0.1)
				(type default)
			)
			(layer "B.Fab")
		)
		(fp_line
			(start 0.12065 0.3048)
			(end 0.67945 0.3048)
			(stroke
				(width 0.1)
				(type default)
			)
			(layer "B.Fab")
		)
		(fp_line
			(start 0.67945 -0.305054)
			(end 0.12065 -0.305054)
			(stroke
				(width 0.1)
				(type default)
			)
			(layer "B.Fab")
		)
		(fp_line
			(start 0.67945 0.3048)
			(end 0.67945 -0.305054)
			(stroke
				(width 0.1)
				(type default)
			)
			(layer "B.Fab")
		)
		(pad "1" smd circle
			(at 0.40005 0 180)
			(size 0 0)
			(layers "B.Cu" "B.Mask" "B.Paste")
			(net "PVDDCR_CPU1_P1")
		)
		(pad "2" smd circle
			(at -0.40005 0 180)
			(size 0 0)
			(layers "B.Cu" "B.Mask" "B.Paste")
			(net "GND")
		)
	)
	(footprint ""
		(layer "B.Cu")
		(at 254.635 -332.867 180)
		(property "Reference" "R842"
			(at 0 0 0)
			(layer "B.SilkS")
			(hide yes)
			(effects
				(font
					(size 1.27 1.27)
				)
				(justify mirror)
			)
		)
		(property "Value" ""
			(at 0 0 0)
			(layer "B.Fab")
			(effects
				(font
					(size 1.27 1.27)
				)
				(justify mirror)
			)
		)
		(duplicate_pad_numbers_are_jumpers no)
		(fp_line
			(start 0.32512 0.175006)
			(end 0.32512 -0.175006)
			(stroke
				(width 0.1)
				(type default)
			)
			(layer "B.Fab")
		)
		(fp_line
			(start 0.32512 -0.175006)
			(end -0.32512 -0.175006)
			(stroke
				(width 0.1)
				(type default)
			)
			(layer "B.Fab")
		)
		(fp_line
			(start -0.32512 0.175006)
			(end 0.32512 0.175006)
			(stroke
				(width 0.1)
				(type default)
			)
			(layer "B.Fab")
		)
		(fp_line
			(start -0.32512 -0.175006)
			(end -0.32512 0.175006)
			(stroke
				(width 0.1)
				(type default)
			)
			(layer "B.Fab")
		)
		(pad "1" smd rect
			(at 0.2667 0)
			(size 0.3048 0.381)
			(layers "B.Cu" "B.Mask" "B.Paste")
			(net "P1V8_AUX")
		)
		(pad "2" smd rect
			(at -0.2667 0 180)
			(size 0.3048 0.381)
			(layers "B.Cu" "B.Mask" "B.Paste")
			(net "RT_ROM_SMB_MUX_ADDR2")
		)
	)
	(footprint ""
		(layer "B.Cu")
		(at 236.8169 -248.285 180)
		(property "Reference" "R328"
			(at 0 0 0)
			(layer "B.SilkS")
			(hide yes)
			(effects
				(font
					(size 1.27 1.27)
				)
				(justify mirror)
			)
		)
		(property "Value" ""
			(at 0 0 0)
			(layer "B.Fab")
			(effects
				(font
					(size 1.27 1.27)
				)
				(justify mirror)
			)
		)
		(duplicate_pad_numbers_are_jumpers no)
		(fp_line
			(start 0.7874 0.4064)
			(end 0.7874 -0.4064)
			(stroke
				(width 0.1524)
				(type default)
			)
			(layer "B.SilkS")
		)
		(fp_line
			(start 0.7874 -0.4064)
			(end -0.7874 -0.4064)
			(stroke
				(width 0.1524)
				(type default)
			)
			(layer "B.SilkS")
		)
		(fp_line
			(start -0.7874 0.4064)
			(end 0.7874 0.4064)
			(stroke
				(width 0.1524)
				(type default)
			)
			(layer "B.SilkS")
		)
		(fp_line
			(start -0.7874 -0.4064)
			(end -0.7874 0.4064)
			(stroke
				(width 0.1524)
				(type default)
			)
			(layer "B.SilkS")
		)
		(fp_line
			(start 0.67945 0.3048)
			(end 0.67945 -0.305054)
			(stroke
				(width 0.1)
				(type default)
			)
			(layer "B.Fab")
		)
		(fp_line
			(start 0.67945 -0.305054)
			(end 0.12065 -0.305054)
			(stroke
				(width 0.1)
				(type default)
			)
			(layer "B.Fab")
		)
		(fp_line
			(start 0.12065 0.3048)
			(end 0.67945 0.3048)
			(stroke
				(width 0.1)
				(type default)
			)
			(layer "B.Fab")
		)
		(fp_line
			(start 0.12065 0.2794)
			(end 0.12065 0.3048)
			(stroke
				(width 0.1)
				(type default)
			)
			(layer "B.Fab")
		)
		(fp_line
			(start 0.12065 -0.2794)
			(end -0.12065 -0.2794)
			(stroke
				(width 0.1)
				(type default)
			)
			(layer "B.Fab")
		)
		(fp_line
			(start 0.12065 -0.305054)
			(end 0.12065 -0.2794)
			(stroke
				(width 0.1)
				(type default)
			)
			(layer "B.Fab")
		)
		(fp_line
			(start -0.120396 0.3048)
			(end -0.120396 0.2794)
			(stroke
				(width 0.1)
				(type default)
			)
			(layer "B.Fab")
		)
		(fp_line
			(start -0.120396 0.2794)
			(end 0.12065 0.2794)
			(stroke
				(width 0.1)
				(type default)
			)
			(layer "B.Fab")
		)
		(fp_line
			(start -0.12065 -0.2794)
			(end -0.12065 -0.3048)
			(stroke
				(width 0.1)
				(type default)
			)
			(layer "B.Fab")
		)
		(fp_line
			(start -0.12065 -0.3048)
			(end -0.67945 -0.3048)
			(stroke
				(width 0.1)
				(type default)
			)
			(layer "B.Fab")
		)
		(fp_line
			(start -0.67945 0.3048)
			(end -0.120396 0.3048)
			(stroke
				(width 0.1)
				(type default)
			)
			(layer "B.Fab")
		)
		(fp_line
			(start -0.67945 -0.3048)
			(end -0.67945 0.3048)
			(stroke
				(width 0.1)
				(type default)
			)
			(layer "B.Fab")
		)
		(pad "1" smd rect
			(at 0.40005 0 180)
			(size 0.4572 0.508)
			(layers "B.Cu" "B.Mask" "B.Paste")
			(net "SMB_APML_CPU0_MUX2_SDA")
		)
		(pad "2" smd rect
			(at -0.40005 0 180)
			(size 0.4572 0.508)
			(layers "B.Cu" "B.Mask" "B.Paste")
			(net "SMB_APML_CPU0_SDA")
		)
	)
)
